(kicad_pcb
	(version 20260206)
	(generator "pcbnew")
	(generator_version "10.0")
	(general
		(thickness 1.6)
		(legacy_teardrops no)
	)
	(paper "A4")
	(title_block
		(title "01162023_DA0F0TEBIF0_F0T_Expander_BD_F_brd_V02_OCP.brd")
		(comment 1 "Grand Teton / footprints 1488-1494 of 9728")
	)
	(layers
		(0 "F.Cu" signal "TOP")
		(4 "In1.Cu" signal "GND")
		(6 "In2.Cu" signal "VCC")
		(8 "In3.Cu" signal "VCC1")
		(10 "In4.Cu" signal "GND1")
		(12 "In5.Cu" signal "IN1")
		(14 "In6.Cu" signal "GND2")
		(16 "In7.Cu" signal "IN2")
		(18 "In8.Cu" signal "GND3")
		(20 "In9.Cu" signal "IN3")
		(22 "In10.Cu" signal "GND4")
		(24 "In11.Cu" signal "IN4")
		(26 "In12.Cu" signal "GND5")
		(28 "In13.Cu" signal "IN5")
		(30 "In14.Cu" signal "GND6")
		(32 "In15.Cu" signal "IN6")
		(34 "In16.Cu" signal "GND7")
		(2 "B.Cu" signal "BOTTOM")
		(9 "F.Adhes" user "F.Adhesive")
		(11 "B.Adhes" user "B.Adhesive")
		(13 "F.Paste" user "Package Geometry/Pastemask Top")
		(15 "B.Paste" user "Package Geometry/Pastemask Bottom")
		(5 "F.SilkS" user "Ref Des/Silkscreen Top")
		(7 "B.SilkS" user "Ref Des/Silkscreen Bottom")
		(1 "F.Mask" user "Board Geometry/Soldermask Top")
		(3 "B.Mask" user "Board Geometry/Soldermask Bottom")
		(17 "Dwgs.User" user "User.Drawings")
		(19 "Cmts.User" user "User.Comments")
		(21 "Eco1.User" user "User.Eco1")
		(23 "Eco2.User" user "User.Eco2")
		(25 "Edge.Cuts" user "Board Geometry/Outline")
		(27 "Margin" user)
		(31 "F.CrtYd" user "Package Geometry/Place Bound Top")
		(29 "B.CrtYd" user "Package Geometry/Place Bound Bottom")
		(35 "F.Fab" user "Ref Des/Assembly Top")
		(33 "B.Fab" user "Ref Des/Assembly Bottom")
	)
	(footprint ""
		(layer "F.Cu")
		(at 130.753612 -162.003994 -90)
		(property "Reference" "R948"
			(at 0 0 270)
			(layer "F.SilkS")
			(hide yes)
			(effects
				(font
					(size 1.27 1.27)
				)
			)
		)
		(property "Value" ""
			(at 0 0 270)
			(layer "F.Fab")
			(effects
				(font
					(size 1.27 1.27)
				)
			)
		)
		(duplicate_pad_numbers_are_jumpers no)
		(fp_line
			(start -0.7874 0.4064)
			(end -0.7874 -0.4064)
			(stroke
				(width 0.1524)
				(type default)
			)
			(layer "F.SilkS")
		)
		(fp_line
			(start 0.7874 0.4064)
			(end -0.7874 0.4064)
			(stroke
				(width 0.1524)
				(type default)
			)
			(layer "F.SilkS")
		)
		(fp_line
			(start -0.7874 -0.4064)
			(end 0.7874 -0.4064)
			(stroke
				(width 0.1524)
				(type default)
			)
			(layer "F.SilkS")
		)
		(fp_line
			(start 0.7874 -0.4064)
			(end 0.7874 0.4064)
			(stroke
				(width 0.1524)
				(type default)
			)
			(layer "F.SilkS")
		)
		(fp_line
			(start -0.67945 0.3048)
			(end -0.67945 -0.305054)
			(stroke
				(width 0.1)
				(type default)
			)
			(layer "F.Fab")
		)
		(fp_line
			(start -0.12065 0.3048)
			(end -0.67945 0.3048)
			(stroke
				(width 0.1)
				(type default)
			)
			(layer "F.Fab")
		)
		(fp_line
			(start 0.120396 0.3048)
			(end 0.120396 0.2794)
			(stroke
				(width 0.1)
				(type default)
			)
			(layer "F.Fab")
		)
		(fp_line
			(start 0.67945 0.3048)
			(end 0.120396 0.3048)
			(stroke
				(width 0.1)
				(type default)
			)
			(layer "F.Fab")
		)
		(fp_line
			(start -0.12065 0.2794)
			(end -0.12065 0.3048)
			(stroke
				(width 0.1)
				(type default)
			)
			(layer "F.Fab")
		)
		(fp_line
			(start 0.120396 0.2794)
			(end -0.12065 0.2794)
			(stroke
				(width 0.1)
				(type default)
			)
			(layer "F.Fab")
		)
		(fp_line
			(start -0.12065 -0.2794)
			(end 0.12065 -0.2794)
			(stroke
				(width 0.1)
				(type default)
			)
			(layer "F.Fab")
		)
		(fp_line
			(start 0.12065 -0.2794)
			(end 0.12065 -0.3048)
			(stroke
				(width 0.1)
				(type default)
			)
			(layer "F.Fab")
		)
		(fp_line
			(start 0.12065 -0.3048)
			(end 0.67945 -0.3048)
			(stroke
				(width 0.1)
				(type default)
			)
			(layer "F.Fab")
		)
		(fp_line
			(start 0.67945 -0.3048)
			(end 0.67945 0.3048)
			(stroke
				(width 0.1)
				(type default)
			)
			(layer "F.Fab")
		)
		(fp_line
			(start -0.67945 -0.305054)
			(end -0.12065 -0.305054)
			(stroke
				(width 0.1)
				(type default)
			)
			(layer "F.Fab")
		)
		(fp_line
			(start -0.12065 -0.305054)
			(end -0.12065 -0.2794)
			(stroke
				(width 0.1)
				(type default)
			)
			(layer "F.Fab")
		)
		(pad "1" smd circle
			(at -0.40005 0 270)
			(size 0 0)
			(layers "F.Cu" "F.Mask" "F.Paste")
			(net "GND")
		)
		(pad "2" smd circle
			(at 0.40005 0 270)
			(size 0 0)
			(layers "F.Cu" "F.Mask" "F.Paste")
			(net "P12V_NIC2_CO_EN")
		)
	)
	(footprint ""
		(layer "F.Cu")
		(at 273.401282 -55.78475 -90)
		(property "Reference" "PD42"
			(at 4.07035 2.128012 90)
			(unlocked yes)
			(layer "F.SilkS")
			(effects
				(font
					(size 0.7874 0.5842)
					(thickness 0.1524)
				)
				(justify left)
			)
		)
		(property "Value" ""
			(at 0 0 270)
			(layer "F.Fab")
			(effects
				(font
					(size 1.27 1.27)
				)
			)
		)
		(duplicate_pad_numbers_are_jumpers no)
		(fp_line
			(start -3.400044 1.459992)
			(end -3.400044 -1.459992)
			(stroke
				(width 0.1524)
				(type default)
			)
			(layer "F.SilkS")
		)
		(fp_line
			(start 4.107942 1.459992)
			(end -3.400044 1.459992)
			(stroke
				(width 0.1524)
				(type default)
			)
			(layer "F.SilkS")
		)
		(fp_line
			(start -3.400044 -1.459992)
			(end 4.107942 -1.459992)
			(stroke
				(width 0.1524)
				(type default)
			)
			(layer "F.SilkS")
		)
		(fp_line
			(start 4.107942 -1.459992)
			(end 4.107942 1.459992)
			(stroke
				(width 0.1524)
				(type default)
			)
			(layer "F.SilkS")
		)
		(fp_poly
			(pts
				(xy 4.107942 -1.459992) (xy 4.107942 1.459992) (xy 3.308096 1.459992) (xy 3.308096 -1.459992)
			)
			(stroke
				(width 0)
				(type default)
			)
			(fill yes)
			(layer "F.SilkS")
		)
		(fp_line
			(start -2.29997 1.459992)
			(end -2.29997 -1.459992)
			(stroke
				(width 0.1)
				(type default)
			)
			(layer "F.Fab")
		)
		(fp_line
			(start 2.29997 1.459992)
			(end -2.29997 1.459992)
			(stroke
				(width 0.1)
				(type default)
			)
			(layer "F.Fab")
		)
		(fp_line
			(start -2.29997 -1.459992)
			(end 2.29997 -1.459992)
			(stroke
				(width 0.1)
				(type default)
			)
			(layer "F.Fab")
		)
		(fp_line
			(start 2.29997 -1.459992)
			(end 2.29997 1.459992)
			(stroke
				(width 0.1)
				(type default)
			)
			(layer "F.Fab")
		)
		(fp_text user "-"
			(at 5.4102 0.29845 90)
			(unlocked yes)
			(layer "F.SilkS")
			(effects
				(font
					(size 1.905 1.4224)
					(thickness 0.1524)
				)
				(justify left)
			)
		)
		(fp_text user "+"
			(at -4.7752 -0.12065 270)
			(unlocked yes)
			(layer "F.SilkS")
			(effects
				(font
					(size 1.905 1.4224)
					(thickness 0.1524)
				)
				(justify left)
			)
		)
		(fp_text user "-"
			(at 5.4102 0.29845 90)
			(unlocked yes)
			(layer "F.Fab")
			(effects
				(font
					(size 1.905 1.4224)
					(thickness 0.1524)
				)
				(justify left)
			)
		)
		(fp_text user "+"
			(at -4.7752 -0.12065 270)
			(unlocked yes)
			(layer "F.Fab")
			(effects
				(font
					(size 1.905 1.4224)
					(thickness 0.1524)
				)
				(justify left)
			)
		)
		(pad "A" smd rect
			(at -1.999996 0)
			(size 1.7018 2.5146)
			(layers "F.Cu" "F.Mask" "F.Paste")
			(net "GND")
		)
		(pad "C" smd rect
			(at 1.999996 0)
			(size 1.7018 2.5146)
			(layers "F.Cu" "F.Mask" "F.Paste")
			(net "P12V_SSD9_R")
		)
	)
	(footprint ""
		(layer "F.Cu")
		(at 260.249162 -290.595812 -90)
		(property "Reference" "C3382"
			(at 0 0 270)
			(layer "F.SilkS")
			(hide yes)
			(effects
				(font
					(size 1.27 1.27)
				)
			)
		)
		(property "Value" ""
			(at 0 0 270)
			(layer "F.Fab")
			(effects
				(font
					(size 1.27 1.27)
				)
			)
		)
		(duplicate_pad_numbers_are_jumpers no)
		(fp_line
			(start -0.299974 0.150114)
			(end -0.299974 -0.150114)
			(stroke
				(width 0.1)
				(type default)
			)
			(layer "F.Fab")
		)
		(fp_line
			(start 0.299974 0.150114)
			(end -0.299974 0.150114)
			(stroke
				(width 0.1)
				(type default)
			)
			(layer "F.Fab")
		)
		(fp_line
			(start -0.299974 -0.150114)
			(end 0.299974 -0.150114)
			(stroke
				(width 0.1)
				(type default)
			)
			(layer "F.Fab")
		)
		(fp_line
			(start 0.299974 -0.150114)
			(end 0.299974 0.150114)
			(stroke
				(width 0.1)
				(type default)
			)
			(layer "F.Fab")
		)
		(pad "1" smd rect
			(at -0.2667 0 270)
			(size 0.3048 0.381)
			(layers "F.Cu" "F.Mask" "F.Paste")
			(net "P1V8_PLL0_PEX2")
		)
		(pad "2" smd rect
			(at 0.2667 0 270)
			(size 0.3048 0.381)
			(layers "F.Cu" "F.Mask" "F.Paste")
			(net "GND")
		)
	)
	(footprint ""
		(layer "F.Cu")
		(at 3.88366 -61.487812 180)
		(property "Reference" "R5838"
			(at 0 0 180)
			(layer "F.SilkS")
			(hide yes)
			(effects
				(font
					(size 1.27 1.27)
				)
			)
		)
		(property "Value" ""
			(at 0 0 180)
			(layer "F.Fab")
			(effects
				(font
					(size 1.27 1.27)
				)
			)
		)
		(duplicate_pad_numbers_are_jumpers no)
		(fp_line
			(start 0.7874 0.4064)
			(end -0.7874 0.4064)
			(stroke
				(width 0.1524)
				(type default)
			)
			(layer "F.SilkS")
		)
		(fp_line
			(start 0.7874 -0.4064)
			(end 0.7874 0.4064)
			(stroke
				(width 0.1524)
				(type default)
			)
			(layer "F.SilkS")
		)
		(fp_line
			(start -0.7874 0.4064)
			(end -0.7874 -0.4064)
			(stroke
				(width 0.1524)
				(type default)
			)
			(layer "F.SilkS")
		)
		(fp_line
			(start -0.7874 -0.4064)
			(end 0.7874 -0.4064)
			(stroke
				(width 0.1524)
				(type default)
			)
			(layer "F.SilkS")
		)
		(fp_line
			(start 0.67945 0.3048)
			(end 0.120396 0.3048)
			(stroke
				(width 0.1)
				(type default)
			)
			(layer "F.Fab")
		)
		(fp_line
			(start 0.67945 -0.3048)
			(end 0.67945 0.3048)
			(stroke
				(width 0.1)
				(type default)
			)
			(layer "F.Fab")
		)
		(fp_line
			(start 0.12065 -0.2794)
			(end 0.12065 -0.3048)
			(stroke
				(width 0.1)
				(type default)
			)
			(layer "F.Fab")
		)
		(fp_line
			(start 0.12065 -0.3048)
			(end 0.67945 -0.3048)
			(stroke
				(width 0.1)
				(type default)
			)
			(layer "F.Fab")
		)
		(fp_line
			(start 0.120396 0.3048)
			(end 0.120396 0.2794)
			(stroke
				(width 0.1)
				(type default)
			)
			(layer "F.Fab")
		)
		(fp_line
			(start 0.120396 0.2794)
			(end -0.12065 0.2794)
			(stroke
				(width 0.1)
				(type default)
			)
			(layer "F.Fab")
		)
		(fp_line
			(start -0.12065 0.3048)
			(end -0.67945 0.3048)
			(stroke
				(width 0.1)
				(type default)
			)
			(layer "F.Fab")
		)
		(fp_line
			(start -0.12065 0.2794)
			(end -0.12065 0.3048)
			(stroke
				(width 0.1)
				(type default)
			)
			(layer "F.Fab")
		)
		(fp_line
			(start -0.12065 -0.2794)
			(end 0.12065 -0.2794)
			(stroke
				(width 0.1)
				(type default)
			)
			(layer "F.Fab")
		)
		(fp_line
			(start -0.12065 -0.305054)
			(end -0.12065 -0.2794)
			(stroke
				(width 0.1)
				(type default)
			)
			(layer "F.Fab")
		)
		(fp_line
			(start -0.67945 0.3048)
			(end -0.67945 -0.305054)
			(stroke
				(width 0.1)
				(type default)
			)
			(layer "F.Fab")
		)
		(fp_line
			(start -0.67945 -0.305054)
			(end -0.12065 -0.305054)
			(stroke
				(width 0.1)
				(type default)
			)
			(layer "F.Fab")
		)
		(pad "1" smd circle
			(at -0.40005 0 180)
			(size 0 0)
			(layers "F.Cu" "F.Mask" "F.Paste")
			(net "PWRGD_P12V_SSD0_D")
		)
		(pad "2" smd circle
			(at 0.40005 0 180)
			(size 0 0)
			(layers "F.Cu" "F.Mask" "F.Paste")
			(net "PWRGD_P12V_SSD0_R")
		)
	)
	(footprint ""
		(layer "F.Cu")
		(at 419.7985 -66.32194 -90)
		(property "Reference" "PC891"
			(at 0 0 270)
			(layer "F.SilkS")
			(hide yes)
			(effects
				(font
					(size 1.27 1.27)
				)
			)
		)
		(property "Value" ""
			(at 0 0 270)
			(layer "F.Fab")
			(effects
				(font
					(size 1.27 1.27)
				)
			)
		)
		(duplicate_pad_numbers_are_jumpers no)
		(fp_line
			(start -0.7874 0.4064)
			(end -0.7874 -0.4064)
			(stroke
				(width 0.1524)
				(type default)
			)
			(layer "F.SilkS")
		)
		(fp_line
			(start 0.7874 0.4064)
			(end -0.7874 0.4064)
			(stroke
				(width 0.1524)
				(type default)
			)
			(layer "F.SilkS")
		)
		(fp_line
			(start -0.7874 -0.4064)
			(end 0.7874 -0.4064)
			(stroke
				(width 0.1524)
				(type default)
			)
			(layer "F.SilkS")
		)
		(fp_line
			(start 0.7874 -0.4064)
			(end 0.7874 0.4064)
			(stroke
				(width 0.1524)
				(type default)
			)
			(layer "F.SilkS")
		)
		(fp_line
			(start -0.67945 0.3048)
			(end -0.67945 -0.305054)
			(stroke
				(width 0.1)
				(type default)
			)
			(layer "F.Fab")
		)
		(fp_line
			(start -0.12065 0.3048)
			(end -0.67945 0.3048)
			(stroke
				(width 0.1)
				(type default)
			)
			(layer "F.Fab")
		)
		(fp_line
			(start 0.120396 0.3048)
			(end 0.120396 0.2794)
			(stroke
				(width 0.1)
				(type default)
			)
			(layer "F.Fab")
		)
		(fp_line
			(start 0.67945 0.3048)
			(end 0.120396 0.3048)
			(stroke
				(width 0.1)
				(type default)
			)
			(layer "F.Fab")
		)
		(fp_line
			(start -0.12065 0.2794)
			(end -0.12065 0.3048)
			(stroke
				(width 0.1)
				(type default)
			)
			(layer "F.Fab")
		)
		(fp_line
			(start 0.120396 0.2794)
			(end -0.12065 0.2794)
			(stroke
				(width 0.1)
				(type default)
			)
			(layer "F.Fab")
		)
		(fp_line
			(start -0.12065 -0.2794)
			(end 0.12065 -0.2794)
			(stroke
				(width 0.1)
				(type default)
			)
			(layer "F.Fab")
		)
		(fp_line
			(start 0.12065 -0.2794)
			(end 0.12065 -0.3048)
			(stroke
				(width 0.1)
				(type default)
			)
			(layer "F.Fab")
		)
		(fp_line
			(start 0.12065 -0.3048)
			(end 0.67945 -0.3048)
			(stroke
				(width 0.1)
				(type default)
			)
			(layer "F.Fab")
		)
		(fp_line
			(start 0.67945 -0.3048)
			(end 0.67945 0.3048)
			(stroke
				(width 0.1)
				(type default)
			)
			(layer "F.Fab")
		)
		(fp_line
			(start -0.67945 -0.305054)
			(end -0.12065 -0.305054)
			(stroke
				(width 0.1)
				(type default)
			)
			(layer "F.Fab")
		)
		(fp_line
			(start -0.12065 -0.305054)
			(end -0.12065 -0.2794)
			(stroke
				(width 0.1)
				(type default)
			)
			(layer "F.Fab")
		)
		(pad "1" smd circle
			(at -0.40005 0 270)
			(size 0 0)
			(layers "F.Cu" "F.Mask" "F.Paste")
			(net "P12V_SSD14_CO_GATE")
		)
		(pad "2" smd circle
			(at 0.40005 0 270)
			(size 0 0)
			(layers "F.Cu" "F.Mask" "F.Paste")
			(net "GND")
		)
	)
	(footprint ""
		(layer "F.Cu")
		(at 365.113824 -241.783108)
		(property "Reference" "R5891"
			(at 0 0 0)
			(layer "F.SilkS")
			(hide yes)
			(effects
				(font
					(size 1.27 1.27)
				)
			)
		)
		(property "Value" ""
			(at 0 0 0)
			(layer "F.Fab")
			(effects
				(font
					(size 1.27 1.27)
				)
			)
		)
		(duplicate_pad_numbers_are_jumpers no)
		(fp_line
			(start -0.7874 -0.4064)
			(end 0.7874 -0.4064)
			(stroke
				(width 0.1524)
				(type default)
			)
			(layer "F.SilkS")
		)
		(fp_line
			(start -0.7874 0.4064)
			(end -0.7874 -0.4064)
			(stroke
				(width 0.1524)
				(type default)
			)
			(layer "F.SilkS")
		)
		(fp_line
			(start 0.7874 -0.4064)
			(end 0.7874 0.4064)
			(stroke
				(width 0.1524)
				(type default)
			)
			(layer "F.SilkS")
		)
		(fp_line
			(start 0.7874 0.4064)
			(end -0.7874 0.4064)
			(stroke
				(width 0.1524)
				(type default)
			)
			(layer "F.SilkS")
		)
		(fp_line
			(start -0.67945 -0.305054)
			(end -0.12065 -0.305054)
			(stroke
				(width 0.1)
				(type default)
			)
			(layer "F.Fab")
		)
		(fp_line
			(start -0.67945 0.3048)
			(end -0.67945 -0.305054)
			(stroke
				(width 0.1)
				(type default)
			)
			(layer "F.Fab")
		)
		(fp_line
			(start -0.12065 -0.305054)
			(end -0.12065 -0.2794)
			(stroke
				(width 0.1)
				(type default)
			)
			(layer "F.Fab")
		)
		(fp_line
			(start -0.12065 -0.2794)
			(end 0.12065 -0.2794)
			(stroke
				(width 0.1)
				(type default)
			)
			(layer "F.Fab")
		)
		(fp_line
			(start -0.12065 0.2794)
			(end -0.12065 0.3048)
			(stroke
				(width 0.1)
				(type default)
			)
			(layer "F.Fab")
		)
		(fp_line
			(start -0.12065 0.3048)
			(end -0.67945 0.3048)
			(stroke
				(width 0.1)
				(type default)
			)
			(layer "F.Fab")
		)
		(fp_line
			(start 0.120396 0.2794)
			(end -0.12065 0.2794)
			(stroke
				(width 0.1)
				(type default)
			)
			(layer "F.Fab")
		)
		(fp_line
			(start 0.120396 0.3048)
			(end 0.120396 0.2794)
			(stroke
				(width 0.1)
				(type default)
			)
			(layer "F.Fab")
		)
		(fp_line
			(start 0.12065 -0.3048)
			(end 0.67945 -0.3048)
			(stroke
				(width 0.1)
				(type default)
			)
			(layer "F.Fab")
		)
		(fp_line
			(start 0.12065 -0.2794)
			(end 0.12065 -0.3048)
			(stroke
				(width 0.1)
				(type default)
			)
			(layer "F.Fab")
		)
		(fp_line
			(start 0.67945 -0.3048)
			(end 0.67945 0.3048)
			(stroke
				(width 0.1)
				(type default)
			)
			(layer "F.Fab")
		)
		(fp_line
			(start 0.67945 0.3048)
			(end 0.120396 0.3048)
			(stroke
				(width 0.1)
				(type default)
			)
			(layer "F.Fab")
		)
		(pad "1" smd circle
			(at -0.40005 0)
			(size 0 0)
			(layers "F.Cu" "F.Mask" "F.Paste")
			(net "JP_FPGA_LED")
		)
		(pad "2" smd circle
			(at 0.40005 0)
			(size 0 0)
			(layers "F.Cu" "F.Mask" "F.Paste")
			(net "P3V3_LED")
		)
	)
	(footprint ""
		(layer "F.Cu")
		(at 107.817666 -92.368878 90)
		(property "Reference" "R1134"
			(at 0 0 90)
			(layer "F.SilkS")
			(hide yes)
			(effects
				(font
					(size 1.27 1.27)
				)
			)
		)
		(property "Value" ""
			(at 0 0 90)
			(layer "F.Fab")
			(effects
				(font
					(size 1.27 1.27)
				)
			)
		)
		(duplicate_pad_numbers_are_jumpers no)
		(fp_line
			(start 0.7874 -0.4064)
			(end 0.7874 0.4064)
			(stroke
				(width 0.1524)
				(type default)
			)
			(layer "F.SilkS")
		)
		(fp_line
			(start -0.7874 -0.4064)
			(end 0.7874 -0.4064)
			(stroke
				(width 0.1524)
				(type default)
			)
			(layer "F.SilkS")
		)
		(fp_line
			(start 0.7874 0.4064)
			(end -0.7874 0.4064)
			(stroke
				(width 0.1524)
				(type default)
			)
			(layer "F.SilkS")
		)
		(fp_line
			(start -0.7874 0.4064)
			(end -0.7874 -0.4064)
			(stroke
				(width 0.1524)
				(type default)
			)
			(layer "F.SilkS")
		)
		(fp_line
			(start -0.12065 -0.305054)
			(end -0.12065 -0.2794)
			(stroke
				(width 0.1)
				(type default)
			)
			(layer "F.Fab")
		)
		(fp_line
			(start -0.67945 -0.305054)
			(end -0.12065 -0.305054)
			(stroke
				(width 0.1)
				(type default)
			)
			(layer "F.Fab")
		)
		(fp_line
			(start 0.67945 -0.3048)
			(end 0.67945 0.3048)
			(stroke
				(width 0.1)
				(type default)
			)
			(layer "F.Fab")
		)
		(fp_line
			(start 0.12065 -0.3048)
			(end 0.67945 -0.3048)
			(stroke
				(width 0.1)
				(type default)
			)
			(layer "F.Fab")
		)
		(fp_line
			(start 0.12065 -0.2794)
			(end 0.12065 -0.3048)
			(stroke
				(width 0.1)
				(type default)
			)
			(layer "F.Fab")
		)
		(fp_line
			(start -0.12065 -0.2794)
			(end 0.12065 -0.2794)
			(stroke
				(width 0.1)
				(type default)
			)
			(layer "F.Fab")
		)
		(fp_line
			(start 0.120396 0.2794)
			(end -0.12065 0.2794)
			(stroke
				(width 0.1)
				(type default)
			)
			(layer "F.Fab")
		)
		(fp_line
			(start -0.12065 0.2794)
			(end -0.12065 0.3048)
			(stroke
				(width 0.1)
				(type default)
			)
			(layer "F.Fab")
		)
		(fp_line
			(start 0.67945 0.3048)
			(end 0.120396 0.3048)
			(stroke
				(width 0.1)
				(type default)
			)
			(layer "F.Fab")
		)
		(fp_line
			(start 0.120396 0.3048)
			(end 0.120396 0.2794)
			(stroke
				(width 0.1)
				(type default)
			)
			(layer "F.Fab")
		)
		(fp_line
			(start -0.12065 0.3048)
			(end -0.67945 0.3048)
			(stroke
				(width 0.1)
				(type default)
			)
			(layer "F.Fab")
		)
		(fp_line
			(start -0.67945 0.3048)
			(end -0.67945 -0.305054)
			(stroke
				(width 0.1)
				(type default)
			)
			(layer "F.Fab")
		)
		(pad "1" smd circle
			(at -0.40005 0 90)
			(size 0 0)
			(layers "F.Cu" "F.Mask" "F.Paste")
			(net "PU_9ZXL0851_0_7_100M")
		)
		(pad "2" smd circle
			(at 0.40005 0 90)
			(size 0 0)
			(layers "F.Cu" "F.Mask" "F.Paste")
			(net "GND")
		)
	)
)
